(kicad_pcb
	(version 20260206)
	(generator "pcbnew")
	(generator_version "10.0")
	(general
		(thickness 1.6)
		(legacy_teardrops no)
	)
	(paper "A4")
	(title_block
		(title "pdpb — Lightning_PDPB_BRD.brd")
		(comment 1 "Lightning (Wiwynn / Facebook NVMe JBOF) / footprints 690-696 of 1140")
	)
	(layers
		(0 "F.Cu" signal "TOP")
		(4 "In1.Cu" signal "L2GND")
		(6 "In2.Cu" signal "L3")
		(8 "In3.Cu" signal "L4VCC")
		(10 "In4.Cu" signal "L5VCC")
		(12 "In5.Cu" signal "L6")
		(14 "In6.Cu" signal "L7GND")
		(2 "B.Cu" signal "BOTTOM")
		(9 "F.Adhes" user "F.Adhesive")
		(11 "B.Adhes" user "B.Adhesive")
		(13 "F.Paste" user "Package Geometry/Pastemask Top")
		(15 "B.Paste" user "Package Geometry/Pastemask Bottom")
		(5 "F.SilkS" user "Ref Des/Silkscreen Top")
		(7 "B.SilkS" user "Ref Des/Silkscreen Bottom")
		(1 "F.Mask" user "Board Geometry/Soldermask Top")
		(3 "B.Mask" user "Board Geometry/Soldermask Bottom")
		(17 "Dwgs.User" user "User.Drawings")
		(19 "Cmts.User" user "User.Comments")
		(21 "Eco1.User" user "User.Eco1")
		(23 "Eco2.User" user "User.Eco2")
		(25 "Edge.Cuts" user "Board Geometry/Outline")
		(27 "Margin" user)
		(31 "F.CrtYd" user "Package Geometry/Place Bound Top")
		(29 "B.CrtYd" user "Package Geometry/Place Bound Bottom")
		(35 "F.Fab" user "Ref Des/Assembly Top")
		(33 "B.Fab" user "Ref Des/Assembly Bottom")
	)
	(footprint ""
		(layer "F.Cu")
		(at 217.043 -391.795 -90)
		(property "Reference" "R386"
			(at 0 0 270)
			(layer "F.SilkS")
			(hide yes)
			(effects
				(font
					(size 1.27 1.27)
				)
			)
		)
		(property "Value" "0R2J-2-GP"
			(at 0.064008 -3.993896 270)
			(unlocked yes)
			(layer "F.Fab")
			(hide yes)
			(effects
				(font
					(size 1.016 1.016)
					(thickness 0.1524)
				)
			)
		)
		(property "Device Type" "R402H16"
			(at 0.064008 -5.517896 270)
			(unlocked yes)
			(layer "F.Fab")
			(hide yes)
			(effects
				(font
					(size 1.016 1.016)
					(thickness 0.1524)
				)
			)
		)
		(duplicate_pad_numbers_are_jumpers no)
		(fp_line
			(start -0.508 -0.9398)
			(end -0.508 0.9398)
			(stroke
				(width 0.1524)
				(type default)
			)
			(layer "F.SilkS")
		)
		(fp_line
			(start 0.508 -0.9398)
			(end -0.508 -0.9398)
			(stroke
				(width 0.1524)
				(type default)
			)
			(layer "F.SilkS")
		)
		(fp_rect
			(start -0.508 0.9398)
			(end 0.508 -0.9398)
			(stroke
				(width 0)
				(type default)
			)
			(fill no)
			(layer "F.CrtYd")
		)
		(fp_rect
			(start -0.508 0.9398)
			(end 0.508 -0.9398)
			(stroke
				(width 0)
				(type default)
			)
			(fill no)
			(layer "F.Fab")
		)
		(pad "1" smd custom
			(at 0 -0.4445 270)
			(size 0.1397 0.1397)
			(layers "F.Cu" "F.Mask" "F.Paste")
			(net "SDA_DR1_R")
			(options
				(clearance outline)
				(anchor circle)
			)
			(primitives
				(gr_poly
					(pts
						(arc
							(start -0.1778 -0.2794)
							(mid -0.249642 -0.249642)
							(end -0.2794 -0.1778)
						)
						(arc
							(start -0.2794 0.1778)
							(mid -0.249642 0.249642)
							(end -0.1778 0.2794)
						)
						(arc
							(start 0.1778 0.2794)
							(mid 0.249642 0.249642)
							(end 0.2794 0.1778)
						)
						(arc
							(start 0.2794 -0.1778)
							(mid 0.249642 -0.249642)
							(end 0.1778 -0.2794)
						)
					)
					(width 0)
					(fill yes)
				)
			)
		)
		(pad "2" smd custom
			(at 0 0.4445 270)
			(size 0.1397 0.1397)
			(layers "F.Cu" "F.Mask" "F.Paste")
			(net "SDA_DR1")
			(options
				(clearance outline)
				(anchor circle)
			)
			(primitives
				(gr_poly
					(pts
						(arc
							(start -0.1778 -0.2794)
							(mid -0.249642 -0.249642)
							(end -0.2794 -0.1778)
						)
						(arc
							(start -0.2794 0.1778)
							(mid -0.249642 0.249642)
							(end -0.1778 0.2794)
						)
						(arc
							(start 0.1778 0.2794)
							(mid 0.249642 0.249642)
							(end 0.2794 0.1778)
						)
						(arc
							(start 0.2794 -0.1778)
							(mid 0.249642 -0.249642)
							(end 0.1778 -0.2794)
						)
					)
					(width 0)
					(fill yes)
				)
			)
		)
	)
	(footprint ""
		(layer "F.Cu")
		(at 29.845 -423.164 90)
		(property "Reference" "R409"
			(at 0 0 90)
			(layer "F.SilkS")
			(hide yes)
			(effects
				(font
					(size 1.27 1.27)
				)
			)
		)
		(property "Value" "0R2J-2-GP"
			(at 0.064008 -3.993896 90)
			(unlocked yes)
			(layer "F.Fab")
			(hide yes)
			(effects
				(font
					(size 1.016 1.016)
					(thickness 0.1524)
				)
			)
		)
		(property "Device Type" "R402H16"
			(at 0.064008 -5.517896 90)
			(unlocked yes)
			(layer "F.Fab")
			(hide yes)
			(effects
				(font
					(size 1.016 1.016)
					(thickness 0.1524)
				)
			)
		)
		(duplicate_pad_numbers_are_jumpers no)
		(fp_line
			(start 0.508 -0.9398)
			(end -0.508 -0.9398)
			(stroke
				(width 0.1524)
				(type default)
			)
			(layer "F.SilkS")
		)
		(fp_line
			(start -0.508 -0.9398)
			(end -0.508 0.9398)
			(stroke
				(width 0.1524)
				(type default)
			)
			(layer "F.SilkS")
		)
		(fp_rect
			(start -0.508 0.9398)
			(end 0.508 -0.9398)
			(stroke
				(width 0)
				(type default)
			)
			(fill no)
			(layer "F.CrtYd")
		)
		(fp_rect
			(start -0.508 0.9398)
			(end 0.508 -0.9398)
			(stroke
				(width 0)
				(type default)
			)
			(fill no)
			(layer "F.Fab")
		)
		(pad "1" smd custom
			(at 0 -0.4445 90)
			(size 0.1397 0.1397)
			(layers "F.Cu" "F.Mask" "F.Paste")
			(net "SDA_DR10_R")
			(options
				(clearance outline)
				(anchor circle)
			)
			(primitives
				(gr_poly
					(pts
						(arc
							(start -0.1778 -0.2794)
							(mid -0.249642 -0.249642)
							(end -0.2794 -0.1778)
						)
						(arc
							(start -0.2794 0.1778)
							(mid -0.249642 0.249642)
							(end -0.1778 0.2794)
						)
						(arc
							(start 0.1778 0.2794)
							(mid 0.249642 0.249642)
							(end 0.2794 0.1778)
						)
						(arc
							(start 0.2794 -0.1778)
							(mid 0.249642 -0.249642)
							(end 0.1778 -0.2794)
						)
					)
					(width 0)
					(fill yes)
				)
			)
		)
		(pad "2" smd custom
			(at 0 0.4445 90)
			(size 0.1397 0.1397)
			(layers "F.Cu" "F.Mask" "F.Paste")
			(net "SDA_DR10")
			(options
				(clearance outline)
				(anchor circle)
			)
			(primitives
				(gr_poly
					(pts
						(arc
							(start -0.1778 -0.2794)
							(mid -0.249642 -0.249642)
							(end -0.2794 -0.1778)
						)
						(arc
							(start -0.2794 0.1778)
							(mid -0.249642 0.249642)
							(end -0.1778 0.2794)
						)
						(arc
							(start 0.1778 0.2794)
							(mid 0.249642 0.249642)
							(end 0.2794 0.1778)
						)
						(arc
							(start 0.2794 -0.1778)
							(mid 0.249642 -0.249642)
							(end 0.1778 -0.2794)
						)
					)
					(width 0)
					(fill yes)
				)
			)
		)
	)
	(footprint ""
		(layer "F.Cu")
		(at 226.114102 -350.061784 180)
		(property "Reference" "R9929"
			(at 0 0 180)
			(layer "F.SilkS")
			(hide yes)
			(effects
				(font
					(size 1.27 1.27)
				)
			)
		)
		(property "Value" "4K7R2J-2-GP"
			(at 0.064008 -3.993896 180)
			(unlocked yes)
			(layer "F.Fab")
			(hide yes)
			(effects
				(font
					(size 1.016 1.016)
					(thickness 0.1524)
				)
			)
		)
		(property "Device Type" "R402H16"
			(at 0.064008 -5.517896 180)
			(unlocked yes)
			(layer "F.Fab")
			(hide yes)
			(effects
				(font
					(size 1.016 1.016)
					(thickness 0.1524)
				)
			)
		)
		(duplicate_pad_numbers_are_jumpers no)
		(fp_line
			(start 0.508 -0.9398)
			(end -0.508 -0.9398)
			(stroke
				(width 0.1524)
				(type default)
			)
			(layer "F.SilkS")
		)
		(fp_line
			(start -0.508 -0.9398)
			(end -0.508 0.9398)
			(stroke
				(width 0.1524)
				(type default)
			)
			(layer "F.SilkS")
		)
		(fp_rect
			(start -0.508 0.9398)
			(end 0.508 -0.9398)
			(stroke
				(width 0)
				(type default)
			)
			(fill no)
			(layer "F.CrtYd")
		)
		(fp_rect
			(start -0.508 0.9398)
			(end 0.508 -0.9398)
			(stroke
				(width 0)
				(type default)
			)
			(fill no)
			(layer "F.Fab")
		)
		(pad "1" smd custom
			(at 0 -0.4445 180)
			(size 0.1397 0.1397)
			(layers "F.Cu" "F.Mask" "F.Paste")
			(net "P3V3")
			(options
				(clearance outline)
				(anchor circle)
			)
			(primitives
				(gr_poly
					(pts
						(arc
							(start -0.1778 -0.2794)
							(mid -0.249642 -0.249642)
							(end -0.2794 -0.1778)
						)
						(arc
							(start -0.2794 0.1778)
							(mid -0.249642 0.249642)
							(end -0.1778 0.2794)
						)
						(arc
							(start 0.1778 0.2794)
							(mid 0.249642 0.249642)
							(end 0.2794 0.1778)
						)
						(arc
							(start 0.2794 -0.1778)
							(mid 0.249642 -0.249642)
							(end 0.1778 -0.2794)
						)
					)
					(width 0)
					(fill yes)
				)
			)
		)
		(pad "2" smd custom
			(at 0 0.4445 180)
			(size 0.1397 0.1397)
			(layers "F.Cu" "F.Mask" "F.Paste")
			(net "ATTN_LED_DR1_MOS_N")
			(options
				(clearance outline)
				(anchor circle)
			)
			(primitives
				(gr_poly
					(pts
						(arc
							(start -0.1778 -0.2794)
							(mid -0.249642 -0.249642)
							(end -0.2794 -0.1778)
						)
						(arc
							(start -0.2794 0.1778)
							(mid -0.249642 0.249642)
							(end -0.1778 0.2794)
						)
						(arc
							(start 0.1778 0.2794)
							(mid 0.249642 0.249642)
							(end 0.2794 0.1778)
						)
						(arc
							(start 0.2794 -0.1778)
							(mid 0.249642 -0.249642)
							(end 0.1778 -0.2794)
						)
					)
					(width 0)
					(fill yes)
				)
			)
		)
	)
	(footprint ""
		(layer "F.Cu")
		(at 97.155 -115.062)
		(property "Reference" "R9605"
			(at 0 0 0)
			(layer "F.SilkS")
			(hide yes)
			(effects
				(font
					(size 1.27 1.27)
				)
			)
		)
		(property "Value" "10R2F-L-GP"
			(at 0.064008 -3.993896 0)
			(unlocked yes)
			(layer "F.Fab")
			(hide yes)
			(effects
				(font
					(size 1.016 1.016)
					(thickness 0.1524)
				)
			)
		)
		(property "Device Type" "R402H14"
			(at 0.064008 -5.517896 0)
			(unlocked yes)
			(layer "F.Fab")
			(hide yes)
			(effects
				(font
					(size 1.016 1.016)
					(thickness 0.1524)
				)
			)
		)
		(duplicate_pad_numbers_are_jumpers no)
		(fp_line
			(start -0.508 -0.9398)
			(end -0.508 0.9398)
			(stroke
				(width 0.1524)
				(type default)
			)
			(layer "F.SilkS")
		)
		(fp_line
			(start 0.508 -0.9398)
			(end -0.508 -0.9398)
			(stroke
				(width 0.1524)
				(type default)
			)
			(layer "F.SilkS")
		)
		(fp_rect
			(start -0.508 0.9398)
			(end 0.508 -0.9398)
			(stroke
				(width 0)
				(type default)
			)
			(fill no)
			(layer "F.CrtYd")
		)
		(fp_rect
			(start -0.508 0.9398)
			(end 0.508 -0.9398)
			(stroke
				(width 0)
				(type default)
			)
			(fill no)
			(layer "F.Fab")
		)
		(pad "1" smd custom
			(at 0 -0.4445)
			(size 0.1397 0.1397)
			(layers "F.Cu" "F.Mask" "F.Paste")
			(net "SSD8_CLK0_OE_N")
			(options
				(clearance outline)
				(anchor circle)
			)
			(primitives
				(gr_poly
					(pts
						(arc
							(start -0.1778 -0.2794)
							(mid -0.249642 -0.249642)
							(end -0.2794 -0.1778)
						)
						(arc
							(start -0.2794 0.1778)
							(mid -0.249642 0.249642)
							(end -0.1778 0.2794)
						)
						(arc
							(start 0.1778 0.2794)
							(mid 0.249642 0.249642)
							(end 0.2794 0.1778)
						)
						(arc
							(start 0.2794 -0.1778)
							(mid 0.249642 -0.249642)
							(end 0.1778 -0.2794)
						)
					)
					(width 0)
					(fill yes)
				)
			)
		)
		(pad "2" smd custom
			(at 0 0.4445)
			(size 0.1397 0.1397)
			(layers "F.Cu" "F.Mask" "F.Paste")
			(net "SSD8_CLK0_OE_R_N")
			(options
				(clearance outline)
				(anchor circle)
			)
			(primitives
				(gr_poly
					(pts
						(arc
							(start -0.1778 -0.2794)
							(mid -0.249642 -0.249642)
							(end -0.2794 -0.1778)
						)
						(arc
							(start -0.2794 0.1778)
							(mid -0.249642 0.249642)
							(end -0.1778 0.2794)
						)
						(arc
							(start 0.1778 0.2794)
							(mid 0.249642 0.249642)
							(end 0.2794 0.1778)
						)
						(arc
							(start 0.2794 -0.1778)
							(mid 0.249642 -0.249642)
							(end 0.1778 -0.2794)
						)
					)
					(width 0)
					(fill yes)
				)
			)
		)
	)
	(footprint ""
		(layer "F.Cu")
		(at 39.02075 -102.64775)
		(property "Reference" "R9754"
			(at 0 0 0)
			(layer "F.SilkS")
			(hide yes)
			(effects
				(font
					(size 1.27 1.27)
				)
			)
		)
		(property "Value" "4K7R2J-2-GP"
			(at 0.064008 -3.993896 0)
			(unlocked yes)
			(layer "F.Fab")
			(hide yes)
			(effects
				(font
					(size 1.016 1.016)
					(thickness 0.1524)
				)
			)
		)
		(property "Device Type" "R402H16"
			(at 0.064008 -5.517896 0)
			(unlocked yes)
			(layer "F.Fab")
			(hide yes)
			(effects
				(font
					(size 1.016 1.016)
					(thickness 0.1524)
				)
			)
		)
		(duplicate_pad_numbers_are_jumpers no)
		(fp_line
			(start -0.508 -0.9398)
			(end -0.508 0.9398)
			(stroke
				(width 0.1524)
				(type default)
			)
			(layer "F.SilkS")
		)
		(fp_line
			(start 0.508 -0.9398)
			(end -0.508 -0.9398)
			(stroke
				(width 0.1524)
				(type default)
			)
			(layer "F.SilkS")
		)
		(fp_rect
			(start -0.508 0.9398)
			(end 0.508 -0.9398)
			(stroke
				(width 0)
				(type default)
			)
			(fill no)
			(layer "F.CrtYd")
		)
		(fp_rect
			(start -0.508 0.9398)
			(end 0.508 -0.9398)
			(stroke
				(width 0)
				(type default)
			)
			(fill no)
			(layer "F.Fab")
		)
		(pad "1" smd custom
			(at 0 -0.4445)
			(size 0.1397 0.1397)
			(layers "F.Cu" "F.Mask" "F.Paste")
			(net "P3V3")
			(options
				(clearance outline)
				(anchor circle)
			)
			(primitives
				(gr_poly
					(pts
						(arc
							(start -0.1778 -0.2794)
							(mid -0.249642 -0.249642)
							(end -0.2794 -0.1778)
						)
						(arc
							(start -0.2794 0.1778)
							(mid -0.249642 0.249642)
							(end -0.1778 0.2794)
						)
						(arc
							(start 0.1778 0.2794)
							(mid 0.249642 0.249642)
							(end 0.2794 0.1778)
						)
						(arc
							(start 0.2794 -0.1778)
							(mid 0.249642 -0.249642)
							(end 0.1778 -0.2794)
						)
					)
					(width 0)
					(fill yes)
				)
			)
		)
		(pad "2" smd custom
			(at 0 0.4445)
			(size 0.1397 0.1397)
			(layers "F.Cu" "F.Mask" "F.Paste")
			(net "SSD13_PWREN")
			(options
				(clearance outline)
				(anchor circle)
			)
			(primitives
				(gr_poly
					(pts
						(arc
							(start -0.1778 -0.2794)
							(mid -0.249642 -0.249642)
							(end -0.2794 -0.1778)
						)
						(arc
							(start -0.2794 0.1778)
							(mid -0.249642 0.249642)
							(end -0.1778 0.2794)
						)
						(arc
							(start 0.1778 0.2794)
							(mid 0.249642 0.249642)
							(end 0.2794 0.1778)
						)
						(arc
							(start 0.2794 -0.1778)
							(mid 0.249642 -0.249642)
							(end 0.1778 -0.2794)
						)
					)
					(width 0)
					(fill yes)
				)
			)
		)
	)
	(footprint ""
		(layer "F.Cu")
		(at 102.616 -204.47 90)
		(property "Reference" "R9082"
			(at 0 0 90)
			(layer "F.SilkS")
			(hide yes)
			(effects
				(font
					(size 1.27 1.27)
				)
			)
		)
		(property "Value" "27R2F-GP"
			(at 0.064008 -3.993896 90)
			(unlocked yes)
			(layer "F.Fab")
			(hide yes)
			(effects
				(font
					(size 1.016 1.016)
					(thickness 0.1524)
				)
			)
		)
		(property "Device Type" "R402H16"
			(at 0.064008 -5.517896 90)
			(unlocked yes)
			(layer "F.Fab")
			(hide yes)
			(effects
				(font
					(size 1.016 1.016)
					(thickness 0.1524)
				)
			)
		)
		(duplicate_pad_numbers_are_jumpers no)
		(fp_line
			(start 0.508 -0.9398)
			(end -0.508 -0.9398)
			(stroke
				(width 0.1524)
				(type default)
			)
			(layer "F.SilkS")
		)
		(fp_line
			(start -0.508 -0.9398)
			(end -0.508 0.9398)
			(stroke
				(width 0.1524)
				(type default)
			)
			(layer "F.SilkS")
		)
		(fp_rect
			(start -0.508 0.9398)
			(end 0.508 -0.9398)
			(stroke
				(width 0)
				(type default)
			)
			(fill no)
			(layer "F.CrtYd")
		)
		(fp_rect
			(start -0.508 0.9398)
			(end 0.508 -0.9398)
			(stroke
				(width 0)
				(type default)
			)
			(fill no)
			(layer "F.Fab")
		)
		(pad "1" smd custom
			(at 0 -0.4445 90)
			(size 0.1397 0.1397)
			(layers "F.Cu" "F.Mask" "F.Paste")
			(net "PE_CLK_100M_DR3_2_R_P")
			(options
				(clearance outline)
				(anchor circle)
			)
			(primitives
				(gr_poly
					(pts
						(arc
							(start -0.1778 -0.2794)
							(mid -0.249642 -0.249642)
							(end -0.2794 -0.1778)
						)
						(arc
							(start -0.2794 0.1778)
							(mid -0.249642 0.249642)
							(end -0.1778 0.2794)
						)
						(arc
							(start 0.1778 0.2794)
							(mid 0.249642 0.249642)
							(end 0.2794 0.1778)
						)
						(arc
							(start 0.2794 -0.1778)
							(mid 0.249642 -0.249642)
							(end 0.1778 -0.2794)
						)
					)
					(width 0)
					(fill yes)
				)
			)
		)
		(pad "2" smd custom
			(at 0 0.4445 90)
			(size 0.1397 0.1397)
			(layers "F.Cu" "F.Mask" "F.Paste")
			(net "PE_CLK100M_DR3_2_P")
			(options
				(clearance outline)
				(anchor circle)
			)
			(primitives
				(gr_poly
					(pts
						(arc
							(start -0.1778 -0.2794)
							(mid -0.249642 -0.249642)
							(end -0.2794 -0.1778)
						)
						(arc
							(start -0.2794 0.1778)
							(mid -0.249642 0.249642)
							(end -0.1778 0.2794)
						)
						(arc
							(start 0.1778 0.2794)
							(mid 0.249642 0.249642)
							(end 0.2794 0.1778)
						)
						(arc
							(start 0.2794 -0.1778)
							(mid 0.249642 -0.249642)
							(end 0.1778 -0.2794)
						)
					)
					(width 0)
					(fill yes)
				)
			)
		)
	)
	(footprint ""
		(layer "F.Cu")
		(at 100.33 -110.236 180)
		(property "Reference" "R9130"
			(at 0 0 180)
			(layer "F.SilkS")
			(hide yes)
			(effects
				(font
					(size 1.27 1.27)
				)
			)
		)
		(property "Value" "27R2F-GP"
			(at 0.064008 -3.993896 180)
			(unlocked yes)
			(layer "F.Fab")
			(hide yes)
			(effects
				(font
					(size 1.016 1.016)
					(thickness 0.1524)
				)
			)
		)
		(property "Device Type" "R402H16"
			(at 0.064008 -5.517896 180)
			(unlocked yes)
			(layer "F.Fab")
			(hide yes)
			(effects
				(font
					(size 1.016 1.016)
					(thickness 0.1524)
				)
			)
		)
		(duplicate_pad_numbers_are_jumpers no)
		(fp_line
			(start 0.508 -0.9398)
			(end -0.508 -0.9398)
			(stroke
				(width 0.1524)
				(type default)
			)
			(layer "F.SilkS")
		)
		(fp_line
			(start -0.508 -0.9398)
			(end -0.508 0.9398)
			(stroke
				(width 0.1524)
				(type default)
			)
			(layer "F.SilkS")
		)
		(fp_rect
			(start -0.508 0.9398)
			(end 0.508 -0.9398)
			(stroke
				(width 0)
				(type default)
			)
			(fill no)
			(layer "F.CrtYd")
		)
		(fp_rect
			(start -0.508 0.9398)
			(end 0.508 -0.9398)
			(stroke
				(width 0)
				(type default)
			)
			(fill no)
			(layer "F.Fab")
		)
		(pad "1" smd custom
			(at 0 -0.4445 180)
			(size 0.1397 0.1397)
			(layers "F.Cu" "F.Mask" "F.Paste")
			(net "PE_CLK_100M_DR8_2_R_P")
			(options
				(clearance outline)
				(anchor circle)
			)
			(primitives
				(gr_poly
					(pts
						(arc
							(start -0.1778 -0.2794)
							(mid -0.249642 -0.249642)
							(end -0.2794 -0.1778)
						)
						(arc
							(start -0.2794 0.1778)
							(mid -0.249642 0.249642)
							(end -0.1778 0.2794)
						)
						(arc
							(start 0.1778 0.2794)
							(mid 0.249642 0.249642)
							(end 0.2794 0.1778)
						)
						(arc
							(start 0.2794 -0.1778)
							(mid 0.249642 -0.249642)
							(end 0.1778 -0.2794)
						)
					)
					(width 0)
					(fill yes)
				)
			)
		)
		(pad "2" smd custom
			(at 0 0.4445 180)
			(size 0.1397 0.1397)
			(layers "F.Cu" "F.Mask" "F.Paste")
			(net "PE_CLK100M_DR8_2_P")
			(options
				(clearance outline)
				(anchor circle)
			)
			(primitives
				(gr_poly
					(pts
						(arc
							(start -0.1778 -0.2794)
							(mid -0.249642 -0.249642)
							(end -0.2794 -0.1778)
						)
						(arc
							(start -0.2794 0.1778)
							(mid -0.249642 0.249642)
							(end -0.1778 0.2794)
						)
						(arc
							(start 0.1778 0.2794)
							(mid 0.249642 0.249642)
							(end 0.2794 0.1778)
						)
						(arc
							(start 0.2794 -0.1778)
							(mid 0.249642 -0.249642)
							(end 0.1778 -0.2794)
						)
					)
					(width 0)
					(fill yes)
				)
			)
		)
	)
)
